FILE_TYPE=LIBRARY_PARTS;
primitive 'SCONN13_502280130CV01';
  pin
    '1':
      PIN_NUMBER='(1)';
      BIDIRECTIONAL='TRUE';
      INPUT_LOAD='(-0.01,0.01)';
      OUTPUT_LOAD='(1.0,-1.0)';
    '2':
      PIN_NUMBER='(2)';
      BIDIRECTIONAL='TRUE';
      INPUT_LOAD='(-0.01,0.01)';
      OUTPUT_LOAD='(1.0,-1.0)';
    '3':
      PIN_NUMBER='(3)';
      BIDIRECTIONAL='TRUE';
      INPUT_LOAD='(-0.01,0.01)';
      OUTPUT_LOAD='(1.0,-1.0)';
    '4':
      PIN_NUMBER='(4)';
      BIDIRECTIONAL='TRUE';
      INPUT_LOAD='(-0.01,0.01)';
      OUTPUT_LOAD='(1.0,-1.0)';
    '5':
      PIN_NUMBER='(5)';
      BIDIRECTIONAL='TRUE';
      INPUT_LOAD='(-0.01,0.01)';
      OUTPUT_LOAD='(1.0,-1.0)';
    '6':
      PIN_NUMBER='(6)';
      BIDIRECTIONAL='TRUE';
      INPUT_LOAD='(-0.01,0.01)';
      OUTPUT_LOAD='(1.0,-1.0)';
    '7':
      PIN_NUMBER='(7)';
      BIDIRECTIONAL='TRUE';
      INPUT_LOAD='(-0.01,0.01)';
      OUTPUT_LOAD='(1.0,-1.0)';
    '8':
      PIN_NUMBER='(8)';
      BIDIRECTIONAL='TRUE';
      INPUT_LOAD='(-0.01,0.01)';
      OUTPUT_LOAD='(1.0,-1.0)';
    '9':
      PIN_NUMBER='(9)';
      BIDIRECTIONAL='TRUE';
      INPUT_LOAD='(-0.01,0.01)';
      OUTPUT_LOAD='(1.0,-1.0)';
    '10':
      PIN_NUMBER='(10)';
      BIDIRECTIONAL='TRUE';
      INPUT_LOAD='(-0.01,0.01)';
      OUTPUT_LOAD='(1.0,-1.0)';
    '11':
      PIN_NUMBER='(11)';
      BIDIRECTIONAL='TRUE';
      INPUT_LOAD='(-0.01,0.01)';
      OUTPUT_LOAD='(1.0,-1.0)';
    '12':
      PIN_NUMBER='(12)';
      BIDIRECTIONAL='TRUE';
      INPUT_LOAD='(-0.01,0.01)';
      OUTPUT_LOAD='(1.0,-1.0)';
    '13':
      PIN_NUMBER='(13)';
      BIDIRECTIONAL='TRUE';
      INPUT_LOAD='(-0.01,0.01)';
      OUTPUT_LOAD='(1.0,-1.0)';
    'G1':
      PIN_NUMBER='(G1)';
      PINUSE='POWER';
      NO_LOAD_CHECK='Both';
      NO_IO_CHECK='Both';
      NO_ASSERT_CHECK='TRUE';
      NO_DIR_CHECK='TRUE';
      ALLOW_CONNECT='TRUE';
    'G2':
      PIN_NUMBER='(G2)';
      PINUSE='POWER';
      NO_LOAD_CHECK='Both';
      NO_IO_CHECK='Both';
      NO_ASSERT_CHECK='TRUE';
      NO_DIR_CHECK='TRUE';
      ALLOW_CONNECT='TRUE';
  end_pin;
  body
    PART_NAME='SCONN13_502280130CV01';
    BODY_NAME='SCONN13_502280130CV01';
    PHYS_DES_PREFIX='J';
    CLASS='IO';
  end_body;
end_primitive;

END.
